# BASEBOARD_FAB2 (Tioga Pass) — schematic netlist excerpt (pin names and nets, part order shuffled) for the footprints in the layout excerpt that follows; sources: Cadence DE-HDL packaged netlist, KiCad conversion of Wiwynn_Tioga_Pass_MB.brd

J9A3  SCONN60_C21100002  CONN  pkg SMLF  page 111
  IO1  = XDP_DEBUG_CONSENT_N
  IO2  = GND
  IO3  = XDP_PREQ_N
  IO4  = TP_XDP_CPU_OBSFN_C0
  IO5  = XDP_PRDY_N
  IO6  = XDP_SPI_PCH_MOSI_BOOT_HALT_N
  IO7  = GND
  IO8  = GND
  IO9  = TP_XDP_OBSDATA_A0
  IO10  = TP_XDP_CPU_OBSDATA_C0
  IO11  = TP_XDP_OBSDATA_A1
  IO12  = TP_XDP_CPU_OBSDATA_C1
  IO13  = GND
  IO14  = GND
  IO15  = TP_XDP_OBSDATA_A2
  IO16  = TP_XDP_CPU_OBSDATA_C2
  IO17  = TP_XDP_OBSDATA_A3
  IO18  = TP_XDP_CPU_OBSDATA_C3
  IO19  = GND
  IO20  = GND
  IO21  = TP_XDP_OBSFN_B0
  IO22  = XDP_OBSFN_B0_MBP6_N
  IO23  = TP_XDP_OBSFN_B1
  IO24  = XDP_OBSFN_B1_MBP7_N
  IO25  = GND
  IO26  = GND
  IO27  = TP_XDP_OBSDATA_B0
  IO28  = TP_XDP_CPU_OBSDATA_D0
  IO29  = TP_XDP_OBSDATA_B1
  IO30  = TP_XDP_CPU_OBSDATA_D1
  IO31  = GND
  IO32  = GND
  IO33  = TP_XDP_OBSDATA_B2
  IO34  = TP_XDP_CPU_OBSDATA_D2
  IO35  = TP_XDP_OBSDATA_B3
  IO36  = TP_XDP_CPU_OBSDATA_D3
  IO37  = GND
  IO38  = GND
  IO39  = XDP_RSMRST_N
  IO40  = CLK_100M_PCH_XDP_DP
  IO41  = XDP_PWRGD_RST_N
  IO42  = CLK_100M_PCH_XDP_DN
  IO43  = P1V05_PCH_STBY
  IO44  = P1V05_PCH_STBY
  IO45  = XDP_CPU_PWR_DEBUG_N
  IO46  = XDP_ITP_PMODE
  IO47  = XDP_SYSPWROK
  IO48  = XDP_RST_CO_N
  IO49  = GND
  IO50  = GND
  IO51  = SMB_HOST_STBY_LVC3_SDA
  IO52  = XDP_TDO
  IO53  = SMB_HOST_STBY_LVC3_SCL
  IO54  = XDP_TRST_N
  IO55  = XDP_PCH_TCK1
  IO56  = XDP_TDI
  IO57  = XDP_CPU_TCK0
  IO58  = XDP_TMS
  IO59  = GND
  IO60  = XDP_PRESENT_N

(kicad_pcb
	(version 20260206)
	(generator "pcbnew")
	(generator_version "10.0")
	(general
		(thickness 1.6)
		(legacy_teardrops no)
	)
	(paper "A4")
	(title_block
		(title "Wiwynn_Tioga_Pass_MB.brd")
		(comment 1 "Tioga Pass / footprint 867 of 4770 (J9A3), pads 1-46 of 62")
	)
	(layers
		(0 "F.Cu" signal "TOP")
		(4 "In1.Cu" signal "L2GND")
		(6 "In2.Cu" signal "L3")
		(8 "In3.Cu" signal "L4GND")
		(10 "In4.Cu" signal "L5")
		(12 "In5.Cu" signal "L6GND")
		(14 "In6.Cu" signal "L7VCC")
		(16 "In7.Cu" signal "L8VCC")
		(18 "In8.Cu" signal "L9GND")
		(20 "In9.Cu" signal "L10")
		(22 "In10.Cu" signal "L11GND")
		(24 "In11.Cu" signal "L12")
		(26 "In12.Cu" signal "L13GND")
		(2 "B.Cu" signal "BOTTOM")
		(9 "F.Adhes" user "F.Adhesive")
		(11 "B.Adhes" user "B.Adhesive")
		(13 "F.Paste" user "Package Geometry/Pastemask Top")
		(15 "B.Paste" user "Package Geometry/Pastemask Bottom")
		(5 "F.SilkS" user "Ref Des/Silkscreen Top")
		(7 "B.SilkS" user "Ref Des/Silkscreen Bottom")
		(1 "F.Mask" user "Board Geometry/Soldermask Top")
		(3 "B.Mask" user "Board Geometry/Soldermask Bottom")
		(17 "Dwgs.User" user "User.Drawings")
		(19 "Cmts.User" user "User.Comments")
		(21 "Eco1.User" user "User.Eco1")
		(23 "Eco2.User" user "User.Eco2")
		(25 "Edge.Cuts" user "Board Geometry/Outline")
		(27 "Margin" user)
		(31 "F.CrtYd" user "Package Geometry/Place Bound Top")
		(29 "B.CrtYd" user "Package Geometry/Place Bound Bottom")
		(35 "F.Fab" user "Ref Des/Assembly Top")
		(33 "B.Fab" user "Ref Des/Assembly Bottom")
	)
	(footprint ""
		(layer "F.Cu")
		(at 462.980532 -135.71982 90.001)
		(property "Reference" "J9A3"
			(at 3.15304 -8.221925 90.001)
			(unlocked yes)
			(layer "F.SilkS")
			(effects
				(font
					(size 0.7874 0.5842)
					(thickness 0.1524)
				)
				(justify left)
			)
		)
		(property "Value" ""
			(at 0 0 90.001)
			(layer "F.Fab")
			(effects
				(font
					(size 1.27 1.27)
				)
			)
		)
		(duplicate_pad_numbers_are_jumpers no)
		(pad "" np_thru_hole circle
			(at -2.810002 -5.530088 90.001)
			(size 0.254 0.254)
			(drill 1.0414)
			(layers "*.Cu" "*.Mask")
			(clearance 0.7112)
			(thermal_gap 0.7112)
		)
		(pad "" np_thru_hole circle
			(at 17.315942 -5.530088 90.001)
			(size 0.254 0.254)
			(drill 1.0414)
			(layers "*.Cu" "*.Mask")
			(clearance 0.7112)
			(thermal_gap 0.7112)
		)
		(pad "1" smd rect
			(at 0 0 90.001)
			(size 0.2794 2.286)
			(layers "F.Cu" "F.Mask" "F.Paste")
			(net "XDP_DEBUG_CONSENT_N")
		)
		(pad "2" smd rect
			(at 0 -5.727954 90.001)
			(size 0.2794 2.286)
			(layers "F.Cu" "F.Mask" "F.Paste")
			(net "GND")
		)
		(pad "3" smd rect
			(at 0.500126 0 90.001)
			(size 0.2794 2.286)
			(layers "F.Cu" "F.Mask" "F.Paste")
			(net "XDP_PREQ_N")
		)
		(pad "4" smd rect
			(at 0.500126 -5.727954 90.001)
			(size 0.2794 2.286)
			(layers "F.Cu" "F.Mask" "F.Paste")
			(net "TP_XDP_CPU_OBSFN_C0")
		)
		(pad "5" smd rect
			(at 0.999998 0 90.001)
			(size 0.2794 2.286)
			(layers "F.Cu" "F.Mask" "F.Paste")
			(net "XDP_PRDY_N")
		)
		(pad "6" smd rect
			(at 0.999998 -5.727954 90.001)
			(size 0.2794 2.286)
			(layers "F.Cu" "F.Mask" "F.Paste")
			(net "XDP_SPI_PCH_MOSI_BOOT_HALT_N")
		)
		(pad "7" smd rect
			(at 1.500124 0 90.001)
			(size 0.2794 2.286)
			(layers "F.Cu" "F.Mask" "F.Paste")
			(net "GND")
		)
		(pad "8" smd rect
			(at 1.500124 -5.727954 90.001)
			(size 0.2794 2.286)
			(layers "F.Cu" "F.Mask" "F.Paste")
			(net "GND")
		)
		(pad "9" smd rect
			(at 1.999996 0 90.001)
			(size 0.2794 2.286)
			(layers "F.Cu" "F.Mask" "F.Paste")
			(net "TP_XDP_OBSDATA_A0")
		)
		(pad "10" smd rect
			(at 1.999996 -5.727954 90.001)
			(size 0.2794 2.286)
			(layers "F.Cu" "F.Mask" "F.Paste")
			(net "TP_XDP_CPU_OBSDATA_C0")
		)
		(pad "11" smd rect
			(at 2.500122 0 90.001)
			(size 0.2794 2.286)
			(layers "F.Cu" "F.Mask" "F.Paste")
			(net "TP_XDP_OBSDATA_A1")
		)
		(pad "12" smd rect
			(at 2.500122 -5.727954 90.001)
			(size 0.2794 2.286)
			(layers "F.Cu" "F.Mask" "F.Paste")
			(net "TP_XDP_CPU_OBSDATA_C1")
		)
		(pad "13" smd rect
			(at 2.999994 0 90.001)
			(size 0.2794 2.286)
			(layers "F.Cu" "F.Mask" "F.Paste")
			(net "GND")
		)
		(pad "14" smd rect
			(at 2.999994 -5.727954 90.001)
			(size 0.2794 2.286)
			(layers "F.Cu" "F.Mask" "F.Paste")
			(net "GND")
		)
		(pad "15" smd rect
			(at 3.50012 0 90.001)
			(size 0.2794 2.286)
			(layers "F.Cu" "F.Mask" "F.Paste")
			(net "TP_XDP_OBSDATA_A2")
		)
		(pad "16" smd rect
			(at 3.50012 -5.727954 90.001)
			(size 0.2794 2.286)
			(layers "F.Cu" "F.Mask" "F.Paste")
			(net "TP_XDP_CPU_OBSDATA_C2")
		)
		(pad "17" smd rect
			(at 3.999992 0 90.001)
			(size 0.2794 2.286)
			(layers "F.Cu" "F.Mask" "F.Paste")
			(net "TP_XDP_OBSDATA_A3")
		)
		(pad "18" smd rect
			(at 3.999992 -5.727954 90.001)
			(size 0.2794 2.286)
			(layers "F.Cu" "F.Mask" "F.Paste")
			(net "TP_XDP_CPU_OBSDATA_C3")
		)
		(pad "19" smd rect
			(at 4.500118 0 90.001)
			(size 0.2794 2.286)
			(layers "F.Cu" "F.Mask" "F.Paste")
			(net "GND")
		)
		(pad "20" smd rect
			(at 4.500118 -5.727954 90.001)
			(size 0.2794 2.286)
			(layers "F.Cu" "F.Mask" "F.Paste")
			(net "GND")
		)
		(pad "21" smd rect
			(at 4.99999 0 90.001)
			(size 0.2794 2.286)
			(layers "F.Cu" "F.Mask" "F.Paste")
			(net "TP_XDP_OBSFN_B0")
		)
		(pad "22" smd rect
			(at 4.99999 -5.727954 90.001)
			(size 0.2794 2.286)
			(layers "F.Cu" "F.Mask" "F.Paste")
			(net "XDP_OBSFN_B0_MBP6_N")
		)
		(pad "23" smd rect
			(at 5.500116 0 90.001)
			(size 0.2794 2.286)
			(layers "F.Cu" "F.Mask" "F.Paste")
			(net "TP_XDP_OBSFN_B1")
		)
		(pad "24" smd rect
			(at 5.500116 -5.727954 90.001)
			(size 0.2794 2.286)
			(layers "F.Cu" "F.Mask" "F.Paste")
			(net "XDP_OBSFN_B1_MBP7_N")
		)
		(pad "25" smd rect
			(at 5.999988 0 90.001)
			(size 0.2794 2.286)
			(layers "F.Cu" "F.Mask" "F.Paste")
			(net "GND")
		)
		(pad "26" smd rect
			(at 5.999988 -5.727954 90.001)
			(size 0.2794 2.286)
			(layers "F.Cu" "F.Mask" "F.Paste")
			(net "GND")
		)
		(pad "27" smd rect
			(at 6.500114 0 90.001)
			(size 0.2794 2.286)
			(layers "F.Cu" "F.Mask" "F.Paste")
			(net "TP_XDP_OBSDATA_B0")
		)
		(pad "28" smd rect
			(at 6.500114 -5.727954 90.001)
			(size 0.2794 2.286)
			(layers "F.Cu" "F.Mask" "F.Paste")
			(net "TP_XDP_CPU_OBSDATA_D0")
		)
		(pad "29" smd rect
			(at 6.999986 0 90.001)
			(size 0.2794 2.286)
			(layers "F.Cu" "F.Mask" "F.Paste")
			(net "TP_XDP_OBSDATA_B1")
		)
		(pad "30" smd rect
			(at 6.999986 -5.727954 90.001)
			(size 0.2794 2.286)
			(layers "F.Cu" "F.Mask" "F.Paste")
			(net "TP_XDP_CPU_OBSDATA_D1")
		)
		(pad "31" smd rect
			(at 7.500112 0 90.001)
			(size 0.2794 2.286)
			(layers "F.Cu" "F.Mask" "F.Paste")
			(net "GND")
		)
		(pad "32" smd rect
			(at 7.500112 -5.727954 90.001)
			(size 0.2794 2.286)
			(layers "F.Cu" "F.Mask" "F.Paste")
			(net "GND")
		)
		(pad "33" smd rect
			(at 7.999984 0 90.001)
			(size 0.2794 2.286)
			(layers "F.Cu" "F.Mask" "F.Paste")
			(net "TP_XDP_OBSDATA_B2")
		)
		(pad "34" smd rect
			(at 7.999984 -5.727954 90.001)
			(size 0.2794 2.286)
			(layers "F.Cu" "F.Mask" "F.Paste")
			(net "TP_XDP_CPU_OBSDATA_D2")
		)
		(pad "35" smd rect
			(at 8.50011 0 90.001)
			(size 0.2794 2.286)
			(layers "F.Cu" "F.Mask" "F.Paste")
			(net "TP_XDP_OBSDATA_B3")
		)
		(pad "36" smd rect
			(at 8.50011 -5.727954 90.001)
			(size 0.2794 2.286)
			(layers "F.Cu" "F.Mask" "F.Paste")
			(net "TP_XDP_CPU_OBSDATA_D3")
		)
		(pad "37" smd rect
			(at 8.999982 0 90.001)
			(size 0.2794 2.286)
			(layers "F.Cu" "F.Mask" "F.Paste")
			(net "GND")
		)
		(pad "38" smd rect
			(at 8.999982 -5.727954 90.001)
			(size 0.2794 2.286)
			(layers "F.Cu" "F.Mask" "F.Paste")
			(net "GND")
		)
		(pad "39" smd rect
			(at 9.500108 0 90.001)
			(size 0.2794 2.286)
			(layers "F.Cu" "F.Mask" "F.Paste")
			(net "XDP_RSMRST_N")
		)
		(pad "40" smd rect
			(at 9.500108 -5.727954 90.001)
			(size 0.2794 2.286)
			(layers "F.Cu" "F.Mask" "F.Paste")
			(net "CLK_100M_PCH_XDP_DP")
		)
		(pad "41" smd rect
			(at 9.99998 0 90.001)
			(size 0.2794 2.286)
			(layers "F.Cu" "F.Mask" "F.Paste")
			(net "XDP_PWRGD_RST_N")
		)
		(pad "42" smd rect
			(at 9.99998 -5.727954 90.001)
			(size 0.2794 2.286)
			(layers "F.Cu" "F.Mask" "F.Paste")
			(net "CLK_100M_PCH_XDP_DN")
		)
		(pad "43" smd rect
			(at 10.500106 0 90.001)
			(size 0.2794 2.286)
			(layers "F.Cu" "F.Mask" "F.Paste")
			(net "P1V05_PCH_STBY")
		)
		(pad "44" smd rect
			(at 10.500106 -5.727954 90.001)
			(size 0.2794 2.286)
			(layers "F.Cu" "F.Mask" "F.Paste")
			(net "P1V05_PCH_STBY")
		)
	)
)
